# BASEBOARD_FAB2 (Tioga Pass) — schematic parts with pin connectivity, parts 2355–2358 of 4751; source: Cadence DE-HDL packaged netlist (pstxprt.dat, pstxnet.dat, pstchip.dat)

J1F1  DM-FCI-CONN76-8R-GP-U-01  pkg CONN-G4  page 181
  A1  PCIE_RX_DP0  UNSPEC  = P3E_CPU1_PE3_MP_RXN<0>
  A2  GND1  POWER  = GND
  A3  PCIE_RX_DP6  UNSPEC  = P3E_CPU1_PE3_MP_RXP<6>
  A4  FAN_TACH3  UNSPEC  = FAN_TACH3_R
  A5  MNG_TX_DP  UNSPEC  = NIC_MDI_MNG_TX_DP
  A6  \pmbus_alert#\  UNSPEC  = IRQ_SML1_PMBUS_ALERT_R_N
  A7  PCIE_TX_DP3  UNSPEC  = P3E_CPU1_PE3_MP_C_TXN<3>
  A8  GND2  POWER  = GND
  B1  PCIE_RX_DN0  UNSPEC  = P3E_CPU1_PE3_MP_RXP<0>
  B2  PCIE_RX_DP3  UNSPEC  = P3E_CPU1_PE3_MP_RXN<3>
  B3  PCIE_RX_DN6  UNSPEC  = P3E_CPU1_PE3_MP_RXN<6>
  B4  FAN_TACH2  UNSPEC  = FAN_TACH2_R
  B5  MNG_TX_DN  UNSPEC  = NIC_MDI_MNG_TX_DN
  B6  PMBUS_DATA  UNSPEC  = SMB_BMC_PMBUS_STBY_LVC3_SDA
  B7  PCIE_TX_DN3  UNSPEC  = P3E_CPU1_PE3_MP_C_TXP<3>
  B8  PCIE_TX_DP0  UNSPEC  = P3E_CPU1_PE3_MP_C_TXN<0>
  C1  GND3  POWER  = GND
  C2  PCIE_RX_DN3  UNSPEC  = P3E_CPU1_PE3_MP_RXP<3>
  C3  GND4  POWER  = GND
  C4  FAN_TACH1  UNSPEC  = FAN_TACH1_R
  C5  GND5  POWER  = GND
  C6  PMBUS_CLK  UNSPEC  = SMB_BMC_PMBUS_STBY_LVC3_SCL
  C7  GND6  POWER  = GND
  C8  PCIE_TX_DN0  UNSPEC  = P3E_CPU1_PE3_MP_C_TXP<0>
  D1  PCIE_RX_DP1  UNSPEC  = P3E_CPU1_PE3_MP_RXN<1>
  D2  GND7  POWER  = GND
  D3  PCIE_RX_DP7  UNSPEC  = P3E_CPU1_PE3_MP_RXN<7>
  D4  FAN_TACH0  UNSPEC  = FAN_TACH0_R
  D5  MNG_RX_DP  UNSPEC  = NIC_MDI_MNG_RX_DP
  D6  GND8  POWER  = GND
  D7  PCIE_TX_DP4  UNSPEC  = P3E_CPU1_PE3_MP_C_TXN<4>
  D8  GND9  POWER  = GND
  E1  PCIE_RX_DN1  UNSPEC  = P3E_CPU1_PE3_MP_RXP<1>
  E2  PCIE_RX_DP4  UNSPEC  = P3E_CPU1_PE3_MP_RXN<4>
  E3  PCIE_RX_DN7  UNSPEC  = P3E_CPU1_PE3_MP_RXP<7>
  E4  \mated_in#\  UNSPEC  = FM_MATED_IN_N
  E5  MNG_RX_DN  UNSPEC  = NIC_MDI_MNG_RX_DN
  E6  PCIE_TX_DP6  UNSPEC  = P3E_CPU1_PE3_MP_C_TXN<6>
  E7  PCIE_TX_DN4  UNSPEC  = P3E_CPU1_PE3_MP_C_TXP<4>
  E8  PCIE_TX_DP1  UNSPEC  = P3E_CPU1_PE3_MP_C_TXN<1>
  F1  GND10  POWER  = GND
  F2  PCIE_RX_DN4  UNSPEC  = P3E_CPU1_PE3_MP_RXP<4>
  F3  GND11  POWER  = GND
  F4  FAN_PWM0  UNSPEC  = FAN_PWM_OUT_SYS0_R1
  F5  MB_SLOT_ID0  UNSPEC  = FM_MB_SLOT_ID0
  F6  PCIE_TX_DN6  UNSPEC  = P3E_CPU1_PE3_MP_C_TXP<6>
  F7  GND12  POWER  = GND
  F8  PCIE_TX_DN1  UNSPEC  = P3E_CPU1_PE3_MP_C_TXP<1>
  G1  PCIE_RX_DP2  UNSPEC  = P3E_CPU1_PE3_MP_RXP<2>
  G2  GND13  POWER  = GND
  G3  COM_TX  UNSPEC  = SPA_MID_DBG_TX_R
  G4  GND14  POWER  = GND
  G5  MB_SLOT_ID1  UNSPEC  = FM_MB_SLOT_ID1
  G6  GND15  POWER  = GND
  G7  PCIE_TX_DP5  UNSPEC  = P3E_CPU1_PE3_MP_C_TXP<5>
  G8  GND16  POWER  = GND
  H1  PCIE_RX_DN2  UNSPEC  = P3E_CPU1_PE3_MP_RXN<2>
  H2  PCIE_RX_DP5  UNSPEC  = P3E_CPU1_PE3_MP_RXP<5>
  H3  COM_RX  UNSPEC  = SPA_MID_DBG_RX_R
  H4  PCIE_CLK_100M_DP  UNSPEC  = CLK_100M_AIRMAX8_PE1_DP
  H5  MB_SLOT_ID2  UNSPEC  = FM_MB_SLOT_ID2
  H6  PCIE_TX_DP7  UNSPEC  = P3E_CPU1_PE3_MP_C_TXP<7>
  H7  PCIE_TX_DN5  UNSPEC  = P3E_CPU1_PE3_MP_C_TXN<5>
  H8  PCIE_TX_DP2  UNSPEC  = P3E_CPU1_PE3_MP_C_TXN<2>
  I1  GND17  POWER  = GND
  I2  PCIE_RX_DN5  UNSPEC  = P3E_CPU1_PE3_MP_RXN<5>
  I3  \mb_on#\  UNSPEC  = FM_ENABLE_FAN_POWER
  I4  PCIE_CLK_100M_DN  UNSPEC  = CLK_100M_AIRMAX8_PE1_DN
  I5  \pcie_perst#\  UNSPEC  = RST_PCIE_MIDPLANE_N
  I6  PCIE_TX_DN7  UNSPEC  = P3E_CPU1_PE3_MP_C_TXN<7>
  I7  GND18  POWER  = GND
  I8  PCIE_TX_DN2  UNSPEC  = P3E_CPU1_PE3_MP_C_TXP<2>
  J2  J2  UNSPEC  = GND
  J4  J4  UNSPEC  = GND
  J6  J6  UNSPEC  = GND
  J8  J8  UNSPEC  = GND

J1F2  LOTES-CON4-S1-GP  pkg CONN-G7  page 161
  1  \1\  UNSPEC  = GND
  2  \2\  UNSPEC  = P12V_FAN
  3  \3\  UNSPEC  = FAN_TACH0_CPU0_D1
  4  \4\  UNSPEC  = FAN_PWM_OUT_SYS0_R
  NP1  NP1  UNSPEC  = NC

J1F3  CONN8_H62179001  CONN  pkg PIP  page 181
  1  IO1  BI  = P3V3_STBY
  2  IO2  BI  = FM_MP_PS_REDUNDANT_LOST_N
  3  IO3  BI  = FM_MP_PS_FAIL_N
  4  IO4  BI  = FM_MATED_IN_N
  5  IO5  BI  = IRQ_SML1_PMBUS_ALERT_R_N
  6  IO6  BI  = SMB_BMC_PMBUS_STBY_LVC3_SDA
  7  IO7  BI  = SMB_BMC_PMBUS_STBY_LVC3_SCL
  8  IO8  BI  = GND

J1G1  SCONN288_H44441004  SCONN  pkg PIP  page 77
  1  \12v\(1)  = P12V_NVDIMM_GHJ
  2  VSS(93)  GROUND  = GND
  3  DQ(4)  BI  = M_G_DQ<5>
  4  VSS(92)  GROUND  = GND
  5  DQ(0)  BI  = M_G_DQ<1>
  6  VSS(91)  GROUND  = GND
  7  DQS9P  BI  = M_G_DQS_DP<9>
  8  DQS9N  BI  = M_G_DQS_DN<9>
  9  VSS(90)  GROUND  = GND
  10  DQ(6)  BI  = M_G_DQ<7>
  11  VSS(89)  GROUND  = GND
  12  DQ(2)  BI  = M_G_DQ<3>
  13  VSS(88)  GROUND  = GND
  14  DQ(12)  BI  = M_G_DQ<13>
  15  VSS(87)  GROUND  = GND
  16  DQ(8)  BI  = M_G_DQ<9>
  17  VSS(86)  GROUND  = GND
  18  DQS10P  BI  = M_G_DQS_DP<10>
  19  DQS10N  BI  = M_G_DQS_DN<10>
  20  VSS(85)  GROUND  = GND
  21  DQ(14)  BI  = M_G_DQ<15>
  22  VSS(84)  GROUND  = GND
  23  DQ(10)  BI  = M_G_DQ<11>
  24  VSS(83)  GROUND  = GND
  25  DQ(20)  BI  = M_G_DQ<21>
  26  VSS(82)  GROUND  = GND
  27  DQ(16)  BI  = M_G_DQ<17>
  28  VSS(81)  GROUND  = GND
  29  DQS11P  BI  = M_G_DQS_DP<11>
  30  DQS11N  BI  = M_G_DQS_DN<11>
  31  VSS(80)  GROUND  = GND
  32  DQ(22)  BI  = M_G_DQ<23>
  33  VSS(79)  GROUND  = GND
  34  DQ(18)  BI  = M_G_DQ<19>
  35  VSS(78)  GROUND  = GND
  36  DQ(28)  BI  = M_G_DQ<29>
  37  VSS(77)  GROUND  = GND
  38  DQ(24)  BI  = M_G_DQ<25>
  39  VSS(76)  GROUND  = GND
  40  DQS12P  BI  = M_G_DQS_DP<12>
  41  DQS12N  BI  = M_G_DQS_DN<12>
  42  VSS(75)  GROUND  = GND
  43  DQ(30)  BI  = M_G_DQ<31>
  44  VSS(74)  GROUND  = GND
  45  DQ(26)  BI  = M_G_DQ<27>
  46  VSS(73)  GROUND  = GND
  47  CB(4)  BI  = M_G_ECC<5>
  48  VSS(72)  GROUND  = GND
  49  CB(0)  BI  = M_G_ECC<1>
  50  VSS(71)  GROUND  = GND
  51  DQS17P  BI  = M_G_DQS_DP<17>
  52  DQS17N  BI  = M_G_DQS_DN<17>
  53  VSS(70)  GROUND  = GND
  54  CB(6)  BI  = M_G_ECC<7>
  55  VSS(69)  GROUND  = GND
  56  CB(2)  BI  = M_G_ECC<3>
  57  VSS(68)  GROUND  = GND
  58  RESET_N  BI  = M_GHJ_RST_N
  59  VDD(25)  POWER  = PVDDQ_GHJ
  60  CKE(0)  BI  = M_G_CKE<0>
  61  VDD(24)  POWER  = PVDDQ_GHJ
  62  ACT_N  BI  = M_G_ACT_N
  63  BG(0)  BI  = M_G_BG<0>
  64  VDD(23)  POWER  = PVDDQ_GHJ
  65  A12  BI  = M_G_MA<12>
  66  A9  BI  = M_G_MA<9>
  67  VDD(22)  POWER  = PVDDQ_GHJ
  68  A8  BI  = M_G_MA<8>
  69  A6  BI  = M_G_MA<6>
  70  VDD(21)  POWER  = PVDDQ_GHJ
  71  A3  BI  = M_G_MA<3>
  72  A1  BI  = M_G_MA<1>
  73  VDD(20)  POWER  = PVDDQ_GHJ
  74  CK0P  BI  = M_G_CLK_DP<0>
  75  CK0N  BI  = M_G_CLK_DN<0>
  76  VDD(19)  POWER  = PVDDQ_GHJ
  77  VTT(1)  POWER  = PVTT_GHJ
  78  EVENT_N  BI  = FM_DIMM_EVENT_COD_N
  79  A0  BI  = M_G_MA<0>
  80  VDD(18)  POWER  = PVDDQ_GHJ
  81  BA(0)  BI  = M_G_BA<0>
  82  A16_RAS_N  BI  = M_G_MA<16>
  83  VDD(17)  POWER  = PVDDQ_GHJ
  84  S0_N  BI  = M_G_CS_N<0>
  85  VDD(16)  POWER  = PVDDQ_GHJ
  86  A15_CAS_N  BI  = M_G_MA<15>
  87  ODT(0)  BI  = M_G_ODT<0>
  88  VDD(15)  POWER  = PVDDQ_GHJ
  89  S1_N  BI  = M_G_CS_N<1>
  90  VDD(14)  POWER  = PVDDQ_GHJ
  91  ODT(1)  BI  = M_G_ODT<1>
  92  VDD(13)  POWER  = PVDDQ_GHJ
  93  S2_N_C(0)  BI  = M_G_CS_N<2>
  94  VSS(67)  GROUND  = GND
  95  DQ(36)  BI  = M_G_DQ<37>
  96  VSS(66)  GROUND  = GND
  97  DQ(32)  BI  = M_G_DQ<33>
  98  VSS(65)  GROUND  = GND
  99  DQS13P  BI  = M_G_DQS_DP<13>
  100  DQS13N  BI  = M_G_DQS_DN<13>
  101  VSS(64)  GROUND  = GND
  102  DQ(38)  BI  = M_G_DQ<39>
  103  VSS(63)  GROUND  = GND
  104  DQ(34)  BI  = M_G_DQ<35>
  105  VSS(62)  GROUND  = GND
  106  DQ(44)  BI  = M_G_DQ<45>
  107  VSS(61)  GROUND  = GND
  108  DQ(40)  BI  = M_G_DQ<41>
  109  VSS(60)  GROUND  = GND
  110  DQS14P  BI  = M_G_DQS_DP<14>
  111  DQS14N  BI  = M_G_DQS_DN<14>
  112  VSS(59)  GROUND  = GND
  113  DQ(46)  BI  = M_G_DQ<47>
  114  VSS(58)  GROUND  = GND
  115  DQ(42)  BI  = M_G_DQ<43>
  116  VSS(57)  GROUND  = GND
  117  DQ(52)  BI  = M_G_DQ<53>
  118  VSS(56)  GROUND  = GND
  119  DQ(48)  BI  = M_G_DQ<49>
  120  VSS(55)  GROUND  = GND
  121  DQS15P  BI  = M_G_DQS_DP<15>
  122  DQS15N  BI  = M_G_DQS_DN<15>
  123  VSS(54)  GROUND  = GND
  124  DQ(54)  BI  = M_G_DQ<55>
  125  VSS(53)  GROUND  = GND
  126  DQ(50)  BI  = M_G_DQ<51>
  127  VSS(52)  GROUND  = GND
  128  DQ(60)  BI  = M_G_DQ<61>
  129  VSS(51)  GROUND  = GND
  130  DQ(56)  BI  = M_G_DQ<57>
  131  VSS(50)  GROUND  = GND
  132  DQS16P  BI  = M_G_DQS_DP<16>
  133  DQS16N  BI  = M_G_DQS_DN<16>
  134  VSS(49)  GROUND  = GND
  135  DQ(62)  BI  = M_G_DQ<63>
  136  VSS(48)  GROUND  = GND
  137  DQ(58)  BI  = M_G_DQ<59>
  138  VSS(47)  GROUND  = GND
  139  SA(0)  BI  = GND
  140  SA(1)  BI  = GND
  141  SCL  BI  = SMB_DDR_GHJ_VPP_SCL
  142  VPP(4)  POWER  = PVPP_GHJ
  143  VPP(3)  POWER  = PVPP_GHJ
  144  RFU(2)  BI  = TP_CH_G_DIMM_G0_RFU_2
  145  \12v\(0)  = P12V_NVDIMM_GHJ
  146  VREFCA  BI  = M_G_VREF
  147  VSS(46)  GROUND  = GND
  148  DQ(5)  BI  = M_G_DQ<4>
  149  VSS(45)  GROUND  = GND
  150  DQ(1)  BI  = M_G_DQ<0>
  151  VSS(44)  GROUND  = GND
  152  DQS0N  BI  = M_G_DQS_DN<0>
  153  DQS0P  BI  = M_G_DQS_DP<0>
  154  VSS(43)  GROUND  = GND
  155  DQ(7)  BI  = M_G_DQ<6>
  156  VSS(42)  GROUND  = GND
  157  DQ(3)  BI  = M_G_DQ<2>
  158  VSS(41)  GROUND  = GND
  159  DQ(13)  BI  = M_G_DQ<12>
  160  VSS(40)  GROUND  = GND
  161  DQ(9)  BI  = M_G_DQ<8>
  162  VSS(39)  GROUND  = GND
  163  DQS1N  BI  = M_G_DQS_DN<1>
  164  DQS1P  BI  = M_G_DQS_DP<1>
  165  VSS(38)  GROUND  = GND
  166  DQ(15)  BI  = M_G_DQ<14>
  167  VSS(37)  GROUND  = GND
  168  DQ(11)  BI  = M_G_DQ<10>
  169  VSS(36)  GROUND  = GND
  170  DQ(21)  BI  = M_G_DQ<20>
  171  VSS(35)  GROUND  = GND
  172  DQ(17)  BI  = M_G_DQ<16>
  173  VSS(34)  GROUND  = GND
  174  DQS2N  BI  = M_G_DQS_DN<2>
  175  DQS2P  BI  = M_G_DQS_DP<2>
  176  VSS(33)  GROUND  = GND
  177  DQ(23)  BI  = M_G_DQ<22>
  178  VSS(32)  GROUND  = GND
  179  DQ(19)  BI  = M_G_DQ<18>
  180  VSS(31)  GROUND  = GND
  181  DQ(29)  BI  = M_G_DQ<28>
  182  VSS(30)  GROUND  = GND
  183  DQ(25)  BI  = M_G_DQ<24>
  184  VSS(29)  GROUND  = GND
  185  DQS3N  BI  = M_G_DQS_DN<3>
  186  DQS3P  BI  = M_G_DQS_DP<3>
  187  VSS(28)  GROUND  = GND
  188  DQ(31)  BI  = M_G_DQ<30>
  189  VSS(27)  GROUND  = GND
  190  DQ(27)  BI  = M_G_DQ<26>
  191  VSS(26)  GROUND  = GND
  192  CB(5)  BI  = M_G_ECC<4>
  193  VSS(25)  GROUND  = GND
  194  CB(1)  BI  = M_G_ECC<0>
  195  VSS(24)  GROUND  = GND
  196  DQS8N  BI  = M_G_DQS_DN<8>
  197  DQS8P  BI  = M_G_DQS_DP<8>
  198  VSS(23)  GROUND  = GND
  199  CB(7)  BI  = M_G_ECC<6>
  200  VSS(22)  GROUND  = GND
  201  CB(3)  BI  = M_G_ECC<2>
  202  VSS(21)  GROUND  = GND
  203  CKE(1)  BI  = M_G_CKE<1>
  204  VDD(12)  POWER  = PVDDQ_GHJ
  205  RFU(0)  BI  = TP_CH_G_DIMM_G0_RFU_0
  206  VDD(11)  POWER  = PVDDQ_GHJ
  207  BG(1)  BI  = M_G_BG<1>
  208  ALERT_N  BI  = M_G_ALERT_N
  209  VDD(10)  POWER  = PVDDQ_GHJ
  210  A11  BI  = M_G_MA<11>
  211  A7  BI  = M_G_MA<7>
  212  VDD(9)  POWER  = PVDDQ_GHJ
  213  A5  BI  = M_G_MA<5>
  214  A4  BI  = M_G_MA<4>
  215  VDD(8)  POWER  = PVDDQ_GHJ
  216  A2  BI  = M_G_MA<2>
  217  VDD(7)  POWER  = PVDDQ_GHJ
  218  CK1P  BI  = M_G_CLK_DP<1>
  219  CK1N  BI  = M_G_CLK_DN<1>
  220  VDD(6)  POWER  = PVDDQ_GHJ
  221  VTT(0)  POWER  = PVTT_GHJ
  222  PAR  BI  = M_G_PAR
  223  VDD(5)  POWER  = PVDDQ_GHJ
  224  BA(1)  BI  = M_G_BA<1>
  225  A10  BI  = M_G_MA<10>
  226  VDD(4)  POWER  = PVDDQ_GHJ
  227  RFU(1)  BI  = TP_CH_G_DIMM_G0_RFU_1
  228  A14_WE_N  BI  = M_G_MA<14>
  229  VDD(3)  POWER  = PVDDQ_GHJ
  230  SAVE_N_NC  BI  = FM_ADR_COMPLETE_GHJ_N
  231  VDD(2)  POWER  = PVDDQ_GHJ
  232  A13  BI  = M_G_MA<13>
  233  VDD(1)  POWER  = PVDDQ_GHJ
  234  A17  BI  = M_G_MA<17>
  235  C(2)  BI  = M_G_C<2>
  236  VDD(0)  POWER  = PVDDQ_GHJ
  237  S3_N_C(1)  BI  = M_G_CS_N<3>
  238  SA(2)  BI  = GND
  239  VSS(20)  GROUND  = GND
  240  DQ(37)  BI  = M_G_DQ<36>
  241  VSS(19)  GROUND  = GND
  242  DQ(33)  BI  = M_G_DQ<32>
  243  VSS(18)  GROUND  = GND
  244  DQS4N  BI  = M_G_DQS_DN<4>
  245  DQS4P  BI  = M_G_DQS_DP<4>
  246  VSS(17)  GROUND  = GND
  247  DQ(39)  BI  = M_G_DQ<38>
  248  VSS(16)  GROUND  = GND
  249  DQ(35)  BI  = M_G_DQ<34>
  250  VSS(15)  GROUND  = GND
  251  DQ(45)  BI  = M_G_DQ<44>
  252  VSS(14)  GROUND  = GND
  253  DQ(41)  BI  = M_G_DQ<40>
  254  VSS(13)  GROUND  = GND
  255  DQS5N  BI  = M_G_DQS_DN<5>
  256  DQS5P  BI  = M_G_DQS_DP<5>
  257  VSS(12)  GROUND  = GND
  258  DQ(47)  BI  = M_G_DQ<46>
  259  VSS(11)  GROUND  = GND
  260  DQ(43)  BI  = M_G_DQ<42>
  261  VSS(10)  GROUND  = GND
  262  DQ(53)  BI  = M_G_DQ<52>
  263  VSS(9)  GROUND  = GND
  264  DQ(49)  BI  = M_G_DQ<48>
  265  VSS(8)  GROUND  = GND
  266  DQS6N  BI  = M_G_DQS_DN<6>
  267  DQS6P  BI  = M_G_DQS_DP<6>
  268  VSS(7)  GROUND  = GND
  269  DQ(55)  BI  = M_G_DQ<54>
  270  VSS(6)  GROUND  = GND
  271  DQ(51)  BI  = M_G_DQ<50>
  272  VSS(5)  GROUND  = GND
  273  DQ(61)  BI  = M_G_DQ<60>
  274  VSS(4)  GROUND  = GND
  275  DQ(57)  BI  = M_G_DQ<56>
  276  VSS(3)  GROUND  = GND
  277  DQS7N  BI  = M_G_DQS_DN<7>
  278  DQS7P  BI  = M_G_DQS_DP<7>
  279  VSS(2)  GROUND  = GND
  280  DQ(63)  BI  = M_G_DQ<62>
  281  VSS(1)  GROUND  = GND
  282  DQ(59)  BI  = M_G_DQ<58>
  283  VSS(0)  GROUND  = GND
  284  VDDSPD  BI  = PVPP_GHJ
  285  SDA  BI  = SMB_DDR_GHJ_VPP_SDA
  286  VPP(1)  POWER  = PVPP_GHJ
  287  VPP(0)  POWER  = PVPP_GHJ
  288  VPP(2)  POWER  = PVPP_GHJ
